(kicad_pcb
	(version 20260206)
	(generator "pcbnew")
	(generator_version "10.0")
	(general
		(thickness 1.6)
		(legacy_teardrops no)
	)
	(paper "A4")
	(title_block
		(title "timecard-production-celestica-r4006 — R4006-B0001-02_R01.brd")
		(comment 1 "Time Appliance Project (Time Card) / footprints 981-985 of 1113")
	)
	(layers
		(0 "F.Cu" signal "TOP")
		(4 "In1.Cu" signal "L02_GND1")
		(6 "In2.Cu" signal "L03_SIG1")
		(8 "In3.Cu" signal "L04_GND2")
		(10 "In4.Cu" signal "L05_VCC1")
		(12 "In5.Cu" signal "L06_VCC2")
		(14 "In6.Cu" signal "L07_GND3")
		(16 "In7.Cu" signal "L08_SIG2")
		(18 "In8.Cu" signal "L09_GND4")
		(2 "B.Cu" signal "BOTTOM")
		(9 "F.Adhes" user "F.Adhesive")
		(11 "B.Adhes" user "B.Adhesive")
		(13 "F.Paste" user "Package Geometry/Pastemask Top")
		(15 "B.Paste" user "Package Geometry/Pastemask Bottom")
		(5 "F.SilkS" user "Ref Des/Silkscreen Top")
		(7 "B.SilkS" user "Ref Des/Silkscreen Bottom")
		(1 "F.Mask" user "Board Geometry/Soldermask Top")
		(3 "B.Mask" user "Board Geometry/Soldermask Bottom")
		(17 "Dwgs.User" user "User.Drawings")
		(19 "Cmts.User" user "User.Comments")
		(21 "Eco1.User" user "User.Eco1")
		(23 "Eco2.User" user "User.Eco2")
		(25 "Edge.Cuts" user "Board Geometry/Outline")
		(27 "Margin" user)
		(31 "F.CrtYd" user "Package Geometry/Place Bound Top")
		(29 "B.CrtYd" user "Package Geometry/Place Bound Bottom")
		(35 "F.Fab" user "Ref Des/Assembly Top")
		(33 "B.Fab" user "Ref Des/Assembly Bottom")
	)
	(footprint ""
		(layer "B.Cu")
		(at 152.781 -70.866)
		(property "Reference" "R82"
			(at 0 -0.97663 0)
			(unlocked yes)
			(layer "B.SilkS")
			(effects
				(font
					(size 0.7874 0.5842)
					(thickness 0.1524)
				)
				(justify mirror)
			)
		)
		(property "Value" "VAL*"
			(at -0.02032 2.13233 0)
			(unlocked yes)
			(layer "B.Fab")
			(hide yes)
			(effects
				(font
					(size 0.7874 0.5842)
					(thickness 0.1524)
				)
				(justify mirror)
			)
		)
		(property "Tolerance" "TOL*"
			(at -0.044704 3.05435 0)
			(unlocked yes)
			(layer "Cmts.User")
			(hide yes)
			(effects
				(font
					(size 0.7874 0.5842)
					(thickness 0.1524)
				)
				(justify mirror)
			)
		)
		(property "User Part Number" "PARTNUM*"
			(at -0.02032 4.024884 0)
			(unlocked yes)
			(layer "Cmts.User")
			(hide yes)
			(effects
				(font
					(size 0.7874 0.5842)
					(thickness 0.1524)
				)
				(justify mirror)
			)
		)
		(property "Device Type" "RESISTOR-G155-133R0-01,33OHM,1%"
			(at -0.008382 1.210564 0)
			(unlocked yes)
			(layer "B.Fab")
			(hide yes)
			(effects
				(font
					(size 0.7874 0.5842)
					(thickness 0.1524)
				)
				(justify mirror)
			)
		)
		(duplicate_pad_numbers_are_jumpers no)
		(fp_line
			(start -1.143 -0.5588)
			(end 1.143 -0.5588)
			(stroke
				(width 0.1)
				(type default)
			)
			(layer "B.SilkS")
		)
		(fp_line
			(start -1.143 0.5588)
			(end -1.143 -0.5588)
			(stroke
				(width 0.1)
				(type default)
			)
			(layer "B.SilkS")
		)
		(fp_line
			(start 1.143 -0.5588)
			(end 1.143 0.5588)
			(stroke
				(width 0.1)
				(type default)
			)
			(layer "B.SilkS")
		)
		(fp_line
			(start 1.143 0.5588)
			(end -1.143 0.5588)
			(stroke
				(width 0.1)
				(type default)
			)
			(layer "B.SilkS")
		)
		(fp_rect
			(start 1.143 0.5588)
			(end -1.143 -0.5588)
			(stroke
				(width 0)
				(type default)
			)
			(fill no)
			(layer "B.CrtYd")
		)
		(fp_line
			(start -0.508 -0.3048)
			(end 0.508 -0.3048)
			(stroke
				(width 0.1)
				(type default)
			)
			(layer "B.Fab")
		)
		(fp_line
			(start -0.508 0.3048)
			(end -0.508 -0.3048)
			(stroke
				(width 0.1)
				(type default)
			)
			(layer "B.Fab")
		)
		(fp_line
			(start 0.508 -0.3048)
			(end 0.508 0.3048)
			(stroke
				(width 0.1)
				(type default)
			)
			(layer "B.Fab")
		)
		(fp_line
			(start 0.508 0.3048)
			(end -0.508 0.3048)
			(stroke
				(width 0.1)
				(type default)
			)
			(layer "B.Fab")
		)
		(pad "1" smd rect
			(at 0.5334 0 180)
			(size 0.7112 0.6096)
			(layers "B.Cu" "B.Mask" "B.Paste")
			(net "R_MAC_UART_TX_FPGA_RX")
		)
		(pad "2" smd rect
			(at -0.5334 0 180)
			(size 0.7112 0.6096)
			(layers "B.Cu" "B.Mask" "B.Paste")
			(net "DBG_UART_MAC_TX")
		)
		(zone
			(layer "B.Cu")
			(hatch none 0.5)
			(connect_pads
				(clearance 0)
			)
			(min_thickness 0.25)
			(keepout
				(tracks allowed)
				(vias not_allowed)
				(pads allowed)
				(copperpour not_allowed)
				(footprints allowed)
			)
			(placement
				(enabled no)
				(sheetname "")
			)
			(fill
				(thermal_gap 0.5)
				(thermal_bridge_width 0.5)
				(island_removal_mode 0)
			)
			(polygon
				(pts
					(xy 152.8572 -70.5612) (xy 152.8572 -71.1708) (xy 152.7048 -71.1708) (xy 152.7048 -70.5612)
				)
			)
		)
	)
	(footprint ""
		(layer "B.Cu")
		(at 18.161 -61.5442 -90)
		(property "Reference" "R282"
			(at 0.381 3.72237 270)
			(unlocked yes)
			(layer "B.SilkS")
			(effects
				(font
					(size 0.7874 0.5842)
					(thickness 0.1524)
				)
				(justify mirror)
			)
		)
		(property "Value" "VAL*"
			(at -0.02032 2.13233 270)
			(unlocked yes)
			(layer "B.Fab")
			(hide yes)
			(effects
				(font
					(size 0.7874 0.5842)
					(thickness 0.1524)
				)
				(justify mirror)
			)
		)
		(property "Tolerance" "TOL*"
			(at -0.044704 3.05435 270)
			(unlocked yes)
			(layer "Cmts.User")
			(hide yes)
			(effects
				(font
					(size 0.7874 0.5842)
					(thickness 0.1524)
				)
				(justify mirror)
			)
		)
		(property "User Part Number" "PARTNUM*"
			(at -0.02032 4.024884 270)
			(unlocked yes)
			(layer "Cmts.User")
			(hide yes)
			(effects
				(font
					(size 0.7874 0.5842)
					(thickness 0.1524)
				)
				(justify mirror)
			)
		)
		(property "Device Type" "RESISTOR-G155-14701-01,4.7KOHMA"
			(at -0.008382 1.210564 270)
			(unlocked yes)
			(layer "B.Fab")
			(hide yes)
			(effects
				(font
					(size 0.7874 0.5842)
					(thickness 0.1524)
				)
				(justify mirror)
			)
		)
		(duplicate_pad_numbers_are_jumpers no)
		(fp_line
			(start -1.143 0.5588)
			(end -1.143 -0.5588)
			(stroke
				(width 0.1)
				(type default)
			)
			(layer "B.SilkS")
		)
		(fp_line
			(start 1.143 0.5588)
			(end -1.143 0.5588)
			(stroke
				(width 0.1)
				(type default)
			)
			(layer "B.SilkS")
		)
		(fp_line
			(start -1.143 -0.5588)
			(end 1.143 -0.5588)
			(stroke
				(width 0.1)
				(type default)
			)
			(layer "B.SilkS")
		)
		(fp_line
			(start 1.143 -0.5588)
			(end 1.143 0.5588)
			(stroke
				(width 0.1)
				(type default)
			)
			(layer "B.SilkS")
		)
		(fp_poly
			(pts
				(xy 1.143 0.5588) (xy -1.143 0.5588) (xy -1.143 -0.5588) (xy 1.143 -0.5588)
			)
			(stroke
				(width 0)
				(type default)
			)
			(fill no)
			(layer "B.CrtYd")
		)
		(fp_line
			(start -0.508 0.3048)
			(end -0.508 -0.3048)
			(stroke
				(width 0.1)
				(type default)
			)
			(layer "B.Fab")
		)
		(fp_line
			(start 0.508 0.3048)
			(end -0.508 0.3048)
			(stroke
				(width 0.1)
				(type default)
			)
			(layer "B.Fab")
		)
		(fp_line
			(start -0.508 -0.3048)
			(end 0.508 -0.3048)
			(stroke
				(width 0.1)
				(type default)
			)
			(layer "B.Fab")
		)
		(fp_line
			(start 0.508 -0.3048)
			(end 0.508 0.3048)
			(stroke
				(width 0.1)
				(type default)
			)
			(layer "B.Fab")
		)
		(pad "1" smd rect
			(at 0.5334 0 90)
			(size 0.7112 0.6096)
			(layers "B.Cu" "B.Mask" "B.Paste")
			(net "XP3R3V_FPGA")
		)
		(pad "2" smd rect
			(at -0.5334 0 90)
			(size 0.7112 0.6096)
			(layers "B.Cu" "B.Mask" "B.Paste")
			(net "ICP10100_I2C_SCL")
		)
		(zone
			(layer "B.Cu")
			(hatch none 0.5)
			(connect_pads
				(clearance 0)
			)
			(min_thickness 0.25)
			(keepout
				(tracks allowed)
				(vias not_allowed)
				(pads allowed)
				(copperpour not_allowed)
				(footprints allowed)
			)
			(placement
				(enabled no)
				(sheetname "")
			)
			(fill
				(thermal_gap 0.5)
				(thermal_bridge_width 0.5)
				(island_removal_mode 0)
			)
			(polygon
				(pts
					(xy 17.8562 -61.468) (xy 18.4658 -61.468) (xy 18.4658 -61.6204) (xy 17.8562 -61.6204)
				)
			)
		)
		(zone
			(layer "B.Cu")
			(hatch none 0.5)
			(connect_pads
				(clearance 0)
			)
			(min_thickness 0.25)
			(keepout
				(tracks not_allowed)
				(vias allowed)
				(pads allowed)
				(copperpour not_allowed)
				(footprints allowed)
			)
			(placement
				(enabled no)
				(sheetname "")
			)
			(fill
				(thermal_gap 0.5)
				(thermal_bridge_width 0.5)
				(island_removal_mode 0)
			)
			(polygon
				(pts
					(xy 17.8562 -61.468) (xy 18.4658 -61.468) (xy 18.4658 -61.6204) (xy 17.8562 -61.6204)
				)
			)
		)
	)
	(footprint ""
		(layer "B.Cu")
		(at 121.073164 -35.772344 90)
		(property "Reference" "C122"
			(at 1.184656 1.069086 270)
			(unlocked yes)
			(layer "B.SilkS")
			(effects
				(font
					(size 0.635 0.4064)
					(thickness 0.1524)
				)
				(justify mirror)
			)
		)
		(property "Value" "VAL*"
			(at 0 3.718306 90)
			(unlocked yes)
			(layer "B.Fab")
			(hide yes)
			(effects
				(font
					(size 0.7874 0.5842)
					(thickness 0.127)
				)
				(justify mirror)
			)
		)
		(property "Tolerance" "TOL*"
			(at 0 4.861306 90)
			(unlocked yes)
			(layer "Cmts.User")
			(hide yes)
			(effects
				(font
					(size 0.7874 0.5842)
					(thickness 0.127)
				)
				(justify mirror)
			)
		)
		(property "User Part Number" "PARTNUM*"
			(at 0 2.575306 90)
			(unlocked yes)
			(layer "Cmts.User")
			(hide yes)
			(effects
				(font
					(size 0.7874 0.5842)
					(thickness 0.127)
				)
				(justify mirror)
			)
		)
		(property "Device Type" "CAPACITOR-G105-0B104-CK,0.1UF,A"
			(at 0 1.432306 90)
			(unlocked yes)
			(layer "B.Fab")
			(hide yes)
			(effects
				(font
					(size 0.7874 0.5842)
					(thickness 0.127)
				)
				(justify mirror)
			)
		)
		(duplicate_pad_numbers_are_jumpers no)
		(fp_line
			(start 0.970026 -0.4699)
			(end -0.970026 -0.4699)
			(stroke
				(width 0.1)
				(type default)
			)
			(layer "B.SilkS")
		)
		(fp_line
			(start -0.970026 -0.4699)
			(end -0.970026 0.4699)
			(stroke
				(width 0.1)
				(type default)
			)
			(layer "B.SilkS")
		)
		(fp_line
			(start 0.970026 0.4699)
			(end 0.970026 -0.4699)
			(stroke
				(width 0.1)
				(type default)
			)
			(layer "B.SilkS")
		)
		(fp_line
			(start -0.970026 0.4699)
			(end 0.970026 0.4699)
			(stroke
				(width 0.1)
				(type default)
			)
			(layer "B.SilkS")
		)
		(fp_poly
			(pts
				(xy 0.970026 0.4699) (xy -0.970026 0.4699) (xy -0.970026 -0.4699) (xy 0.970026 -0.4699)
			)
			(stroke
				(width 0)
				(type default)
			)
			(fill no)
			(layer "B.CrtYd")
		)
		(fp_line
			(start 0.508 -0.3048)
			(end -0.508 -0.3048)
			(stroke
				(width 0.1)
				(type default)
			)
			(layer "B.Fab")
		)
		(fp_line
			(start -0.508 -0.3048)
			(end -0.508 0.3048)
			(stroke
				(width 0.1)
				(type default)
			)
			(layer "B.Fab")
		)
		(fp_line
			(start 0.508 0.3048)
			(end 0.508 -0.3048)
			(stroke
				(width 0.1)
				(type default)
			)
			(layer "B.Fab")
		)
		(fp_line
			(start -0.508 0.3048)
			(end 0.508 0.3048)
			(stroke
				(width 0.1)
				(type default)
			)
			(layer "B.Fab")
		)
		(pad "1" smd circle
			(at 0.500126 0 270)
			(size 0.635 0.635)
			(layers "B.Cu" "B.Mask" "B.Paste")
			(net "XP2R5V_FPGA")
		)
		(pad "2" smd circle
			(at -0.500126 0 270)
			(size 0.635 0.635)
			(layers "B.Cu" "B.Mask" "B.Paste")
			(net "SG")
		)
	)
	(footprint ""
		(layer "B.Cu")
		(at 47.36084 -15.82928 -90)
		(property "Reference" "R23"
			(at -2.45872 0.02921 270)
			(unlocked yes)
			(layer "B.SilkS")
			(effects
				(font
					(size 0.7874 0.5842)
					(thickness 0.1524)
				)
				(justify mirror)
			)
		)
		(property "Value" "VAL*"
			(at -0.02032 2.13233 270)
			(unlocked yes)
			(layer "B.Fab")
			(hide yes)
			(effects
				(font
					(size 0.7874 0.5842)
					(thickness 0.1524)
				)
				(justify mirror)
			)
		)
		(property "Device Type" "RESISTOR-G155-100R0-J0,0OHM,-"
			(at -0.008382 1.210564 270)
			(unlocked yes)
			(layer "B.Fab")
			(hide yes)
			(effects
				(font
					(size 0.7874 0.5842)
					(thickness 0.1524)
				)
				(justify mirror)
			)
		)
		(property "User Part Number" "PARTNUM*"
			(at -0.02032 4.024884 270)
			(unlocked yes)
			(layer "Cmts.User")
			(hide yes)
			(effects
				(font
					(size 0.7874 0.5842)
					(thickness 0.1524)
				)
				(justify mirror)
			)
		)
		(property "Tolerance" "TOL*"
			(at -0.044704 3.05435 270)
			(unlocked yes)
			(layer "Cmts.User")
			(hide yes)
			(effects
				(font
					(size 0.7874 0.5842)
					(thickness 0.1524)
				)
				(justify mirror)
			)
		)
		(duplicate_pad_numbers_are_jumpers no)
		(fp_line
			(start -1.143 0.5588)
			(end -1.143 -0.5588)
			(stroke
				(width 0.1)
				(type default)
			)
			(layer "B.SilkS")
		)
		(fp_line
			(start 1.143 0.5588)
			(end -1.143 0.5588)
			(stroke
				(width 0.1)
				(type default)
			)
			(layer "B.SilkS")
		)
		(fp_line
			(start -1.143 -0.5588)
			(end 1.143 -0.5588)
			(stroke
				(width 0.1)
				(type default)
			)
			(layer "B.SilkS")
		)
		(fp_line
			(start 1.143 -0.5588)
			(end 1.143 0.5588)
			(stroke
				(width 0.1)
				(type default)
			)
			(layer "B.SilkS")
		)
		(fp_rect
			(start 1.143 -0.5588)
			(end -1.143 0.5588)
			(stroke
				(width 0)
				(type default)
			)
			(fill no)
			(layer "B.CrtYd")
		)
		(fp_line
			(start -0.508 0.3048)
			(end -0.508 -0.3048)
			(stroke
				(width 0.1)
				(type default)
			)
			(layer "B.Fab")
		)
		(fp_line
			(start 0.508 0.3048)
			(end -0.508 0.3048)
			(stroke
				(width 0.1)
				(type default)
			)
			(layer "B.Fab")
		)
		(fp_line
			(start -0.508 -0.3048)
			(end 0.508 -0.3048)
			(stroke
				(width 0.1)
				(type default)
			)
			(layer "B.Fab")
		)
		(fp_line
			(start 0.508 -0.3048)
			(end 0.508 0.3048)
			(stroke
				(width 0.1)
				(type default)
			)
			(layer "B.Fab")
		)
		(pad "1" smd rect
			(at 0.5334 0 90)
			(size 0.7112 0.6096)
			(layers "B.Cu" "B.Mask" "B.Paste")
			(net "CARD_PRESENT")
		)
		(pad "2" smd rect
			(at -0.5334 0 90)
			(size 0.7112 0.6096)
			(layers "B.Cu" "B.Mask" "B.Paste")
			(net "UNNAMED_3_CONN64PGF_I61_PRSNT22")
		)
		(zone
			(layer "B.Cu")
			(hatch none 0.5)
			(connect_pads
				(clearance 0)
			)
			(min_thickness 0.25)
			(keepout
				(tracks allowed)
				(vias not_allowed)
				(pads allowed)
				(copperpour not_allowed)
				(footprints allowed)
			)
			(placement
				(enabled no)
				(sheetname "")
			)
			(fill
				(thermal_gap 0.5)
				(thermal_bridge_width 0.5)
				(island_removal_mode 0)
			)
			(polygon
				(pts
					(xy 47.66564 -15.75308) (xy 47.66564 -15.90548) (xy 47.05604 -15.90548) (xy 47.05604 -15.75308)
				)
			)
		)
	)
	(footprint ""
		(layer "B.Cu")
		(at 21.1582 -23.6728 90)
		(property "Reference" "R161"
			(at 3.8862 0.13843 270)
			(unlocked yes)
			(layer "B.SilkS")
			(effects
				(font
					(size 0.7874 0.5842)
					(thickness 0.1524)
				)
				(justify mirror)
			)
		)
		(property "Value" "VAL*"
			(at -0.02032 2.13233 90)
			(unlocked yes)
			(layer "B.Fab")
			(hide yes)
			(effects
				(font
					(size 0.7874 0.5842)
					(thickness 0.1524)
				)
				(justify mirror)
			)
		)
		(property "Tolerance" "TOL*"
			(at -0.044704 3.05435 90)
			(unlocked yes)
			(layer "Cmts.User")
			(hide yes)
			(effects
				(font
					(size 0.7874 0.5842)
					(thickness 0.1524)
				)
				(justify mirror)
			)
		)
		(property "User Part Number" "PARTNUM*"
			(at -0.02032 4.024884 90)
			(unlocked yes)
			(layer "Cmts.User")
			(hide yes)
			(effects
				(font
					(size 0.7874 0.5842)
					(thickness 0.1524)
				)
				(justify mirror)
			)
		)
		(property "Device Type" "RESISTOR-G155-14701-01,4.7KOHMA"
			(at -0.008382 1.210564 90)
			(unlocked yes)
			(layer "B.Fab")
			(hide yes)
			(effects
				(font
					(size 0.7874 0.5842)
					(thickness 0.1524)
				)
				(justify mirror)
			)
		)
		(duplicate_pad_numbers_are_jumpers no)
		(fp_line
			(start 1.143 -0.5588)
			(end 1.143 0.5588)
			(stroke
				(width 0.1)
				(type default)
			)
			(layer "B.SilkS")
		)
		(fp_line
			(start -1.143 -0.5588)
			(end 1.143 -0.5588)
			(stroke
				(width 0.1)
				(type default)
			)
			(layer "B.SilkS")
		)
		(fp_line
			(start 1.143 0.5588)
			(end -1.143 0.5588)
			(stroke
				(width 0.1)
				(type default)
			)
			(layer "B.SilkS")
		)
		(fp_line
			(start -1.143 0.5588)
			(end -1.143 -0.5588)
			(stroke
				(width 0.1)
				(type default)
			)
			(layer "B.SilkS")
		)
		(fp_poly
			(pts
				(xy 1.143 0.5588) (xy -1.143 0.5588) (xy -1.143 -0.5588) (xy 1.143 -0.5588)
			)
			(stroke
				(width 0)
				(type default)
			)
			(fill no)
			(layer "B.CrtYd")
		)
		(fp_line
			(start 0.508 -0.3048)
			(end 0.508 0.3048)
			(stroke
				(width 0.1)
				(type default)
			)
			(layer "B.Fab")
		)
		(fp_line
			(start -0.508 -0.3048)
			(end 0.508 -0.3048)
			(stroke
				(width 0.1)
				(type default)
			)
			(layer "B.Fab")
		)
		(fp_line
			(start 0.508 0.3048)
			(end -0.508 0.3048)
			(stroke
				(width 0.1)
				(type default)
			)
			(layer "B.Fab")
		)
		(fp_line
			(start -0.508 0.3048)
			(end -0.508 -0.3048)
			(stroke
				(width 0.1)
				(type default)
			)
			(layer "B.Fab")
		)
		(pad "1" smd rect
			(at 0.5334 0 270)
			(size 0.7112 0.6096)
			(layers "B.Cu" "B.Mask" "B.Paste")
			(net "UNNAMED_5_24LC16BTISTTSSOP8_I_1")
		)
		(pad "2" smd rect
			(at -0.5334 0 270)
			(size 0.7112 0.6096)
			(layers "B.Cu" "B.Mask" "B.Paste")
			(net "SG")
		)
		(zone
			(layer "B.Cu")
			(hatch none 0.5)
			(connect_pads
				(clearance 0)
			)
			(min_thickness 0.25)
			(keepout
				(tracks allowed)
				(vias not_allowed)
				(pads allowed)
				(copperpour not_allowed)
				(footprints allowed)
			)
			(placement
				(enabled no)
				(sheetname "")
			)
			(fill
				(thermal_gap 0.5)
				(thermal_bridge_width 0.5)
				(island_removal_mode 0)
			)
			(polygon
				(pts
					(xy 21.463 -23.749) (xy 20.8534 -23.749) (xy 20.8534 -23.5966) (xy 21.463 -23.5966)
				)
			)
		)
		(zone
			(layer "B.Cu")
			(hatch none 0.5)
			(connect_pads
				(clearance 0)
			)
			(min_thickness 0.25)
			(keepout
				(tracks not_allowed)
				(vias allowed)
				(pads allowed)
				(copperpour not_allowed)
				(footprints allowed)
			)
			(placement
				(enabled no)
				(sheetname "")
			)
			(fill
				(thermal_gap 0.5)
				(thermal_bridge_width 0.5)
				(island_removal_mode 0)
			)
			(polygon
				(pts
					(xy 21.463 -23.749) (xy 20.8534 -23.749) (xy 20.8534 -23.5966) (xy 21.463 -23.5966)
				)
			)
		)
	)
)
